(kicad_pcb
	(version 20260206)
	(generator "pcbnew")
	(generator_version "10.0")
	(general
		(thickness 1.6)
		(legacy_teardrops no)
	)
	(paper "A4")
	(title_block
		(title "04192023_DAF0TMB3IC0_F0TG_MB_C_brd_V02_OCP.brd")
		(comment 1 "Grand Teton / footprints 7040-7046 of 8354")
	)
	(layers
		(0 "F.Cu" signal "TOP")
		(4 "In1.Cu" signal "GND")
		(6 "In2.Cu" signal "IN1")
		(8 "In3.Cu" signal "GND1")
		(10 "In4.Cu" signal "IN2")
		(12 "In5.Cu" signal "GND2")
		(14 "In6.Cu" signal "IN3")
		(16 "In7.Cu" signal "GND3")
		(18 "In8.Cu" signal "VCC")
		(20 "In9.Cu" signal "VCC1")
		(22 "In10.Cu" signal "GND4")
		(24 "In11.Cu" signal "IN4")
		(26 "In12.Cu" signal "GND5")
		(28 "In13.Cu" signal "IN5")
		(30 "In14.Cu" signal "GND6")
		(32 "In15.Cu" signal "IN6")
		(34 "In16.Cu" signal "GND7")
		(2 "B.Cu" signal "BOTTOM")
		(9 "F.Adhes" user "F.Adhesive")
		(11 "B.Adhes" user "B.Adhesive")
		(13 "F.Paste" user "Package Geometry/Pastemask Top")
		(15 "B.Paste" user "Package Geometry/Pastemask Bottom")
		(5 "F.SilkS" user "Ref Des/Silkscreen Top")
		(7 "B.SilkS" user "Ref Des/Silkscreen Bottom")
		(1 "F.Mask" user "Board Geometry/Soldermask Top")
		(3 "B.Mask" user "Board Geometry/Soldermask Bottom")
		(17 "Dwgs.User" user "User.Drawings")
		(19 "Cmts.User" user "User.Comments")
		(21 "Eco1.User" user "User.Eco1")
		(23 "Eco2.User" user "User.Eco2")
		(25 "Edge.Cuts" user "Board Geometry/Outline")
		(27 "Margin" user)
		(31 "F.CrtYd" user "Package Geometry/Place Bound Top")
		(29 "B.CrtYd" user "Package Geometry/Place Bound Bottom")
		(35 "F.Fab" user "Ref Des/Assembly Top")
		(33 "B.Fab" user "Ref Des/Assembly Bottom")
	)
	(footprint ""
		(layer "B.Cu")
		(at 228.410516 -328.638662 180)
		(property "Reference" "C1088"
			(at 0 0 0)
			(layer "B.SilkS")
			(hide yes)
			(effects
				(font
					(size 1.27 1.27)
				)
				(justify mirror)
			)
		)
		(property "Value" ""
			(at 0 0 0)
			(layer "B.Fab")
			(effects
				(font
					(size 1.27 1.27)
				)
				(justify mirror)
			)
		)
		(duplicate_pad_numbers_are_jumpers no)
		(fp_line
			(start 0.7874 0.4064)
			(end 0.7874 -0.4064)
			(stroke
				(width 0.1524)
				(type default)
			)
			(layer "B.SilkS")
		)
		(fp_line
			(start 0.7874 -0.4064)
			(end -0.7874 -0.4064)
			(stroke
				(width 0.1524)
				(type default)
			)
			(layer "B.SilkS")
		)
		(fp_line
			(start -0.7874 0.4064)
			(end 0.7874 0.4064)
			(stroke
				(width 0.1524)
				(type default)
			)
			(layer "B.SilkS")
		)
		(fp_line
			(start -0.7874 -0.4064)
			(end -0.7874 0.4064)
			(stroke
				(width 0.1524)
				(type default)
			)
			(layer "B.SilkS")
		)
		(fp_line
			(start 0.67945 0.3048)
			(end 0.67945 -0.305054)
			(stroke
				(width 0.1)
				(type default)
			)
			(layer "B.Fab")
		)
		(fp_line
			(start 0.67945 -0.305054)
			(end 0.12065 -0.305054)
			(stroke
				(width 0.1)
				(type default)
			)
			(layer "B.Fab")
		)
		(fp_line
			(start 0.12065 0.3048)
			(end 0.67945 0.3048)
			(stroke
				(width 0.1)
				(type default)
			)
			(layer "B.Fab")
		)
		(fp_line
			(start 0.12065 0.2794)
			(end 0.12065 0.3048)
			(stroke
				(width 0.1)
				(type default)
			)
			(layer "B.Fab")
		)
		(fp_line
			(start 0.12065 -0.2794)
			(end -0.12065 -0.2794)
			(stroke
				(width 0.1)
				(type default)
			)
			(layer "B.Fab")
		)
		(fp_line
			(start 0.12065 -0.305054)
			(end 0.12065 -0.2794)
			(stroke
				(width 0.1)
				(type default)
			)
			(layer "B.Fab")
		)
		(fp_line
			(start -0.120396 0.3048)
			(end -0.120396 0.2794)
			(stroke
				(width 0.1)
				(type default)
			)
			(layer "B.Fab")
		)
		(fp_line
			(start -0.120396 0.2794)
			(end 0.12065 0.2794)
			(stroke
				(width 0.1)
				(type default)
			)
			(layer "B.Fab")
		)
		(fp_line
			(start -0.12065 -0.2794)
			(end -0.12065 -0.3048)
			(stroke
				(width 0.1)
				(type default)
			)
			(layer "B.Fab")
		)
		(fp_line
			(start -0.12065 -0.3048)
			(end -0.67945 -0.3048)
			(stroke
				(width 0.1)
				(type default)
			)
			(layer "B.Fab")
		)
		(fp_line
			(start -0.67945 0.3048)
			(end -0.120396 0.3048)
			(stroke
				(width 0.1)
				(type default)
			)
			(layer "B.Fab")
		)
		(fp_line
			(start -0.67945 -0.3048)
			(end -0.67945 0.3048)
			(stroke
				(width 0.1)
				(type default)
			)
			(layer "B.Fab")
		)
		(pad "1" smd circle
			(at 0.40005 0)
			(size 0 0)
			(layers "B.Cu" "B.Mask" "B.Paste")
			(net "PVDD18_S5_P0_ADC_TIC")
		)
		(pad "2" smd circle
			(at -0.40005 0)
			(size 0 0)
			(layers "B.Cu" "B.Mask" "B.Paste")
			(net "GND")
		)
	)
	(footprint ""
		(layer "B.Cu")
		(at 215.521286 -73.050908)
		(property "Reference" "R76"
			(at 0 0 0)
			(layer "B.SilkS")
			(hide yes)
			(effects
				(font
					(size 1.27 1.27)
				)
				(justify mirror)
			)
		)
		(property "Value" ""
			(at 0 0 0)
			(layer "B.Fab")
			(effects
				(font
					(size 1.27 1.27)
				)
				(justify mirror)
			)
		)
		(duplicate_pad_numbers_are_jumpers no)
		(fp_line
			(start -0.7874 -0.4064)
			(end -0.7874 0.4064)
			(stroke
				(width 0.1524)
				(type default)
			)
			(layer "B.SilkS")
		)
		(fp_line
			(start -0.7874 0.4064)
			(end 0.7874 0.4064)
			(stroke
				(width 0.1524)
				(type default)
			)
			(layer "B.SilkS")
		)
		(fp_line
			(start 0.7874 -0.4064)
			(end -0.7874 -0.4064)
			(stroke
				(width 0.1524)
				(type default)
			)
			(layer "B.SilkS")
		)
		(fp_line
			(start 0.7874 0.4064)
			(end 0.7874 -0.4064)
			(stroke
				(width 0.1524)
				(type default)
			)
			(layer "B.SilkS")
		)
		(fp_line
			(start -0.67945 -0.3048)
			(end -0.67945 0.3048)
			(stroke
				(width 0.1)
				(type default)
			)
			(layer "B.Fab")
		)
		(fp_line
			(start -0.67945 0.3048)
			(end -0.120396 0.3048)
			(stroke
				(width 0.1)
				(type default)
			)
			(layer "B.Fab")
		)
		(fp_line
			(start -0.12065 -0.3048)
			(end -0.67945 -0.3048)
			(stroke
				(width 0.1)
				(type default)
			)
			(layer "B.Fab")
		)
		(fp_line
			(start -0.12065 -0.2794)
			(end -0.12065 -0.3048)
			(stroke
				(width 0.1)
				(type default)
			)
			(layer "B.Fab")
		)
		(fp_line
			(start -0.120396 0.2794)
			(end 0.12065 0.2794)
			(stroke
				(width 0.1)
				(type default)
			)
			(layer "B.Fab")
		)
		(fp_line
			(start -0.120396 0.3048)
			(end -0.120396 0.2794)
			(stroke
				(width 0.1)
				(type default)
			)
			(layer "B.Fab")
		)
		(fp_line
			(start 0.12065 -0.305054)
			(end 0.12065 -0.2794)
			(stroke
				(width 0.1)
				(type default)
			)
			(layer "B.Fab")
		)
		(fp_line
			(start 0.12065 -0.2794)
			(end -0.12065 -0.2794)
			(stroke
				(width 0.1)
				(type default)
			)
			(layer "B.Fab")
		)
		(fp_line
			(start 0.12065 0.2794)
			(end 0.12065 0.3048)
			(stroke
				(width 0.1)
				(type default)
			)
			(layer "B.Fab")
		)
		(fp_line
			(start 0.12065 0.3048)
			(end 0.67945 0.3048)
			(stroke
				(width 0.1)
				(type default)
			)
			(layer "B.Fab")
		)
		(fp_line
			(start 0.67945 -0.305054)
			(end 0.12065 -0.305054)
			(stroke
				(width 0.1)
				(type default)
			)
			(layer "B.Fab")
		)
		(fp_line
			(start 0.67945 0.3048)
			(end 0.67945 -0.305054)
			(stroke
				(width 0.1)
				(type default)
			)
			(layer "B.Fab")
		)
		(pad "1" smd circle
			(at 0.40005 0 180)
			(size 0 0)
			(layers "B.Cu" "B.Mask" "B.Paste")
			(net "NCSI_BMC_TXD1_R")
		)
		(pad "2" smd circle
			(at -0.40005 0 180)
			(size 0 0)
			(layers "B.Cu" "B.Mask" "B.Paste")
			(net "RMII_BMC_OCP_TXD_1")
		)
	)
	(footprint ""
		(layer "B.Cu")
		(at 245.7704 -332.0796 180)
		(property "Reference" "R1514"
			(at 0 0 0)
			(layer "B.SilkS")
			(hide yes)
			(effects
				(font
					(size 1.27 1.27)
				)
				(justify mirror)
			)
		)
		(property "Value" ""
			(at 0 0 0)
			(layer "B.Fab")
			(effects
				(font
					(size 1.27 1.27)
				)
				(justify mirror)
			)
		)
		(duplicate_pad_numbers_are_jumpers no)
		(fp_line
			(start 0.32512 0.175006)
			(end 0.32512 -0.175006)
			(stroke
				(width 0.1)
				(type default)
			)
			(layer "B.Fab")
		)
		(fp_line
			(start 0.32512 -0.175006)
			(end -0.32512 -0.175006)
			(stroke
				(width 0.1)
				(type default)
			)
			(layer "B.Fab")
		)
		(fp_line
			(start -0.32512 0.175006)
			(end 0.32512 0.175006)
			(stroke
				(width 0.1)
				(type default)
			)
			(layer "B.Fab")
		)
		(fp_line
			(start -0.32512 -0.175006)
			(end -0.32512 0.175006)
			(stroke
				(width 0.1)
				(type default)
			)
			(layer "B.Fab")
		)
		(pad "1" smd rect
			(at 0.2667 0)
			(size 0.3048 0.381)
			(layers "B.Cu" "B.Mask" "B.Paste")
			(net "SMB_MUX_RT_R1_SCL")
		)
		(pad "2" smd rect
			(at -0.2667 0 180)
			(size 0.3048 0.381)
			(layers "B.Cu" "B.Mask" "B.Paste")
			(net "SMB_MUX_RT_R2_SCL")
		)
	)
	(footprint ""
		(layer "B.Cu")
		(at 98.493834 -261.947152)
		(property "Reference" "C2116"
			(at 0 0 0)
			(layer "B.SilkS")
			(hide yes)
			(effects
				(font
					(size 1.27 1.27)
				)
				(justify mirror)
			)
		)
		(property "Value" ""
			(at 0 0 0)
			(layer "B.Fab")
			(effects
				(font
					(size 1.27 1.27)
				)
				(justify mirror)
			)
		)
		(duplicate_pad_numbers_are_jumpers no)
		(fp_line
			(start -0.7874 -0.4064)
			(end -0.7874 0.4064)
			(stroke
				(width 0.1524)
				(type default)
			)
			(layer "B.SilkS")
		)
		(fp_line
			(start -0.7874 0.4064)
			(end 0.7874 0.4064)
			(stroke
				(width 0.1524)
				(type default)
			)
			(layer "B.SilkS")
		)
		(fp_line
			(start 0.7874 -0.4064)
			(end -0.7874 -0.4064)
			(stroke
				(width 0.1524)
				(type default)
			)
			(layer "B.SilkS")
		)
		(fp_line
			(start 0.7874 0.4064)
			(end 0.7874 -0.4064)
			(stroke
				(width 0.1524)
				(type default)
			)
			(layer "B.SilkS")
		)
		(fp_line
			(start -0.67945 -0.3048)
			(end -0.67945 0.3048)
			(stroke
				(width 0.1)
				(type default)
			)
			(layer "B.Fab")
		)
		(fp_line
			(start -0.67945 0.3048)
			(end -0.120396 0.3048)
			(stroke
				(width 0.1)
				(type default)
			)
			(layer "B.Fab")
		)
		(fp_line
			(start -0.12065 -0.3048)
			(end -0.67945 -0.3048)
			(stroke
				(width 0.1)
				(type default)
			)
			(layer "B.Fab")
		)
		(fp_line
			(start -0.12065 -0.2794)
			(end -0.12065 -0.3048)
			(stroke
				(width 0.1)
				(type default)
			)
			(layer "B.Fab")
		)
		(fp_line
			(start -0.120396 0.2794)
			(end 0.12065 0.2794)
			(stroke
				(width 0.1)
				(type default)
			)
			(layer "B.Fab")
		)
		(fp_line
			(start -0.120396 0.3048)
			(end -0.120396 0.2794)
			(stroke
				(width 0.1)
				(type default)
			)
			(layer "B.Fab")
		)
		(fp_line
			(start 0.12065 -0.305054)
			(end 0.12065 -0.2794)
			(stroke
				(width 0.1)
				(type default)
			)
			(layer "B.Fab")
		)
		(fp_line
			(start 0.12065 -0.2794)
			(end -0.12065 -0.2794)
			(stroke
				(width 0.1)
				(type default)
			)
			(layer "B.Fab")
		)
		(fp_line
			(start 0.12065 0.2794)
			(end 0.12065 0.3048)
			(stroke
				(width 0.1)
				(type default)
			)
			(layer "B.Fab")
		)
		(fp_line
			(start 0.12065 0.3048)
			(end 0.67945 0.3048)
			(stroke
				(width 0.1)
				(type default)
			)
			(layer "B.Fab")
		)
		(fp_line
			(start 0.67945 -0.305054)
			(end 0.12065 -0.305054)
			(stroke
				(width 0.1)
				(type default)
			)
			(layer "B.Fab")
		)
		(fp_line
			(start 0.67945 0.3048)
			(end 0.67945 -0.305054)
			(stroke
				(width 0.1)
				(type default)
			)
			(layer "B.Fab")
		)
		(pad "1" smd circle
			(at 0.40005 0 180)
			(size 0 0)
			(layers "B.Cu" "B.Mask" "B.Paste")
			(net "PVDDIO_P1")
		)
		(pad "2" smd circle
			(at -0.40005 0 180)
			(size 0 0)
			(layers "B.Cu" "B.Mask" "B.Paste")
			(net "GND")
		)
	)
	(footprint ""
		(layer "B.Cu")
		(at 163.946332 -388.011162 -90)
		(property "Reference" "C430"
			(at 0 0 90)
			(layer "B.SilkS")
			(hide yes)
			(effects
				(font
					(size 1.27 1.27)
				)
				(justify mirror)
			)
		)
		(property "Value" ""
			(at 0 0 90)
			(layer "B.Fab")
			(effects
				(font
					(size 1.27 1.27)
				)
				(justify mirror)
			)
		)
		(duplicate_pad_numbers_are_jumpers no)
		(fp_line
			(start -0.299974 0.150114)
			(end 0.299974 0.150114)
			(stroke
				(width 0.1)
				(type default)
			)
			(layer "B.Fab")
		)
		(fp_line
			(start 0.299974 0.150114)
			(end 0.299974 -0.150114)
			(stroke
				(width 0.1)
				(type default)
			)
			(layer "B.Fab")
		)
		(fp_line
			(start -0.299974 -0.150114)
			(end -0.299974 0.150114)
			(stroke
				(width 0.1)
				(type default)
			)
			(layer "B.Fab")
		)
		(fp_line
			(start 0.299974 -0.150114)
			(end -0.299974 -0.150114)
			(stroke
				(width 0.1)
				(type default)
			)
			(layer "B.Fab")
		)
		(pad "1" smd rect
			(at 0.2667 0 90)
			(size 0.3048 0.381)
			(layers "B.Cu" "B.Mask" "B.Paste")
			(net "P0V9_CPU1_RT2_2A")
		)
		(pad "2" smd rect
			(at -0.2667 0 90)
			(size 0.3048 0.381)
			(layers "B.Cu" "B.Mask" "B.Paste")
			(net "GND")
		)
	)
	(footprint ""
		(layer "B.Cu")
		(at 435.549802 -10.072116 180)
		(property "Reference" "C1240"
			(at 0 0 0)
			(layer "B.SilkS")
			(hide yes)
			(effects
				(font
					(size 1.27 1.27)
				)
				(justify mirror)
			)
		)
		(property "Value" ""
			(at 0 0 0)
			(layer "B.Fab")
			(effects
				(font
					(size 1.27 1.27)
				)
				(justify mirror)
			)
		)
		(duplicate_pad_numbers_are_jumpers no)
		(fp_line
			(start 0.7874 0.4064)
			(end 0.7874 -0.4064)
			(stroke
				(width 0.1524)
				(type default)
			)
			(layer "B.SilkS")
		)
		(fp_line
			(start 0.7874 -0.4064)
			(end -0.7874 -0.4064)
			(stroke
				(width 0.1524)
				(type default)
			)
			(layer "B.SilkS")
		)
		(fp_line
			(start -0.7874 0.4064)
			(end 0.7874 0.4064)
			(stroke
				(width 0.1524)
				(type default)
			)
			(layer "B.SilkS")
		)
		(fp_line
			(start -0.7874 -0.4064)
			(end -0.7874 0.4064)
			(stroke
				(width 0.1524)
				(type default)
			)
			(layer "B.SilkS")
		)
		(fp_line
			(start 0.67945 0.3048)
			(end 0.67945 -0.305054)
			(stroke
				(width 0.1)
				(type default)
			)
			(layer "B.Fab")
		)
		(fp_line
			(start 0.67945 -0.305054)
			(end 0.12065 -0.305054)
			(stroke
				(width 0.1)
				(type default)
			)
			(layer "B.Fab")
		)
		(fp_line
			(start 0.12065 0.3048)
			(end 0.67945 0.3048)
			(stroke
				(width 0.1)
				(type default)
			)
			(layer "B.Fab")
		)
		(fp_line
			(start 0.12065 0.2794)
			(end 0.12065 0.3048)
			(stroke
				(width 0.1)
				(type default)
			)
			(layer "B.Fab")
		)
		(fp_line
			(start 0.12065 -0.2794)
			(end -0.12065 -0.2794)
			(stroke
				(width 0.1)
				(type default)
			)
			(layer "B.Fab")
		)
		(fp_line
			(start 0.12065 -0.305054)
			(end 0.12065 -0.2794)
			(stroke
				(width 0.1)
				(type default)
			)
			(layer "B.Fab")
		)
		(fp_line
			(start -0.120396 0.3048)
			(end -0.120396 0.2794)
			(stroke
				(width 0.1)
				(type default)
			)
			(layer "B.Fab")
		)
		(fp_line
			(start -0.120396 0.2794)
			(end 0.12065 0.2794)
			(stroke
				(width 0.1)
				(type default)
			)
			(layer "B.Fab")
		)
		(fp_line
			(start -0.12065 -0.2794)
			(end -0.12065 -0.3048)
			(stroke
				(width 0.1)
				(type default)
			)
			(layer "B.Fab")
		)
		(fp_line
			(start -0.12065 -0.3048)
			(end -0.67945 -0.3048)
			(stroke
				(width 0.1)
				(type default)
			)
			(layer "B.Fab")
		)
		(fp_line
			(start -0.67945 0.3048)
			(end -0.120396 0.3048)
			(stroke
				(width 0.1)
				(type default)
			)
			(layer "B.Fab")
		)
		(fp_line
			(start -0.67945 -0.3048)
			(end -0.67945 0.3048)
			(stroke
				(width 0.1)
				(type default)
			)
			(layer "B.Fab")
		)
		(pad "1" smd circle
			(at 0.40005 0)
			(size 0 0)
			(layers "B.Cu" "B.Mask" "B.Paste")
			(net "P3V3_OCP_SFF")
		)
		(pad "2" smd circle
			(at -0.40005 0)
			(size 0 0)
			(layers "B.Cu" "B.Mask" "B.Paste")
			(net "GND")
		)
	)
	(footprint ""
		(layer "B.Cu")
		(at 185.324496 -133.577076 90)
		(property "Reference" "R497"
			(at 0 0 90)
			(layer "B.SilkS")
			(hide yes)
			(effects
				(font
					(size 1.27 1.27)
				)
				(justify mirror)
			)
		)
		(property "Value" ""
			(at 0 0 90)
			(layer "B.Fab")
			(effects
				(font
					(size 1.27 1.27)
				)
				(justify mirror)
			)
		)
		(duplicate_pad_numbers_are_jumpers no)
		(fp_line
			(start 0.7874 -0.4064)
			(end -0.7874 -0.4064)
			(stroke
				(width 0.1524)
				(type default)
			)
			(layer "B.SilkS")
		)
		(fp_line
			(start -0.7874 -0.4064)
			(end -0.7874 0.4064)
			(stroke
				(width 0.1524)
				(type default)
			)
			(layer "B.SilkS")
		)
		(fp_line
			(start 0.7874 0.4064)
			(end 0.7874 -0.4064)
			(stroke
				(width 0.1524)
				(type default)
			)
			(layer "B.SilkS")
		)
		(fp_line
			(start -0.7874 0.4064)
			(end 0.7874 0.4064)
			(stroke
				(width 0.1524)
				(type default)
			)
			(layer "B.SilkS")
		)
		(fp_line
			(start 0.67945 -0.305054)
			(end 0.12065 -0.305054)
			(stroke
				(width 0.1)
				(type default)
			)
			(layer "B.Fab")
		)
		(fp_line
			(start 0.12065 -0.305054)
			(end 0.12065 -0.2794)
			(stroke
				(width 0.1)
				(type default)
			)
			(layer "B.Fab")
		)
		(fp_line
			(start -0.12065 -0.3048)
			(end -0.67945 -0.3048)
			(stroke
				(width 0.1)
				(type default)
			)
			(layer "B.Fab")
		)
		(fp_line
			(start -0.67945 -0.3048)
			(end -0.67945 0.3048)
			(stroke
				(width 0.1)
				(type default)
			)
			(layer "B.Fab")
		)
		(fp_line
			(start 0.12065 -0.2794)
			(end -0.12065 -0.2794)
			(stroke
				(width 0.1)
				(type default)
			)
			(layer "B.Fab")
		)
		(fp_line
			(start -0.12065 -0.2794)
			(end -0.12065 -0.3048)
			(stroke
				(width 0.1)
				(type default)
			)
			(layer "B.Fab")
		)
		(fp_line
			(start 0.12065 0.2794)
			(end 0.12065 0.3048)
			(stroke
				(width 0.1)
				(type default)
			)
			(layer "B.Fab")
		)
		(fp_line
			(start -0.120396 0.2794)
			(end 0.12065 0.2794)
			(stroke
				(width 0.1)
				(type default)
			)
			(layer "B.Fab")
		)
		(fp_line
			(start 0.67945 0.3048)
			(end 0.67945 -0.305054)
			(stroke
				(width 0.1)
				(type default)
			)
			(layer "B.Fab")
		)
		(fp_line
			(start 0.12065 0.3048)
			(end 0.67945 0.3048)
			(stroke
				(width 0.1)
				(type default)
			)
			(layer "B.Fab")
		)
		(fp_line
			(start -0.120396 0.3048)
			(end -0.120396 0.2794)
			(stroke
				(width 0.1)
				(type default)
			)
			(layer "B.Fab")
		)
		(fp_line
			(start -0.67945 0.3048)
			(end -0.120396 0.3048)
			(stroke
				(width 0.1)
				(type default)
			)
			(layer "B.Fab")
		)
		(pad "1" smd circle
			(at 0.40005 0 270)
			(size 0 0)
			(layers "B.Cu" "B.Mask" "B.Paste")
			(net "APML_CPU1_ALERT_N")
		)
		(pad "2" smd circle
			(at -0.40005 0 270)
			(size 0 0)
			(layers "B.Cu" "B.Mask" "B.Paste")
			(net "APML_CPU1_ALERT_R_N")
		)
	)
)
